(kicad_pcb
	(version 20260206)
	(generator "pcbnew")
	(generator_version "10.0")
	(general
		(thickness 1.6)
		(legacy_teardrops no)
	)
	(paper "A4")
	(title_block
		(title "Bryce Canyon_F.DPB_16315-1-OCP.brd")
		(comment 1 "Bryce Canyon / footprints 1205-1212 of 2223")
	)
	(layers
		(0 "F.Cu" signal "TOP")
		(4 "In1.Cu" signal "L2GND")
		(6 "In2.Cu" signal "L3")
		(8 "In3.Cu" signal "L4GND")
		(10 "In4.Cu" signal "L5")
		(12 "In5.Cu" signal "L6VCC")
		(14 "In6.Cu" signal "L7VCC")
		(16 "In7.Cu" signal "L8")
		(18 "In8.Cu" signal "L9GND")
		(20 "In9.Cu" signal "L10")
		(22 "In10.Cu" signal "L11GND")
		(2 "B.Cu" signal "BOTTOM")
		(9 "F.Adhes" user "F.Adhesive")
		(11 "B.Adhes" user "B.Adhesive")
		(13 "F.Paste" user "Package Geometry/Pastemask Top")
		(15 "B.Paste" user "Package Geometry/Pastemask Bottom")
		(5 "F.SilkS" user "Ref Des/Silkscreen Top")
		(7 "B.SilkS" user "Ref Des/Silkscreen Bottom")
		(1 "F.Mask" user "Board Geometry/Soldermask Top")
		(3 "B.Mask" user "Board Geometry/Soldermask Bottom")
		(17 "Dwgs.User" user "User.Drawings")
		(19 "Cmts.User" user "User.Comments")
		(21 "Eco1.User" user "User.Eco1")
		(23 "Eco2.User" user "User.Eco2")
		(25 "Edge.Cuts" user "Board Geometry/Outline")
		(27 "Margin" user)
		(31 "F.CrtYd" user "Package Geometry/Place Bound Top")
		(29 "B.CrtYd" user "Package Geometry/Place Bound Bottom")
		(35 "F.Fab" user "Ref Des/Assembly Top")
		(33 "B.Fab" user "Ref Des/Assembly Bottom")
	)
	(footprint ""
		(layer "F.Cu")
		(at 428.192184 -69.434964 -90)
		(property "Reference" "R890"
			(at 0 0 270)
			(layer "F.SilkS")
			(hide yes)
			(effects
				(font
					(size 1.27 1.27)
				)
			)
		)
		(property "Value" "2R6F-GP"
			(at -0.0508 -4.8514 270)
			(unlocked yes)
			(layer "F.Fab")
			(hide yes)
			(effects
				(font
					(size 1.016 1.016)
					(thickness 0.1524)
				)
			)
		)
		(property "Device Type" "R1206H26"
			(at 0 -6.3754 270)
			(unlocked yes)
			(layer "F.Fab")
			(hide yes)
			(effects
				(font
					(size 1.016 1.016)
					(thickness 0.1524)
				)
			)
		)
		(duplicate_pad_numbers_are_jumpers no)
		(fp_line
			(start -1.016 2.2352)
			(end -1.016 -2.2352)
			(stroke
				(width 0.1524)
				(type default)
			)
			(layer "F.SilkS")
		)
		(fp_line
			(start 1.016 2.2352)
			(end -1.016 2.2352)
			(stroke
				(width 0.1524)
				(type default)
			)
			(layer "F.SilkS")
		)
		(fp_line
			(start -1.016 -2.2352)
			(end 1.016 -2.2352)
			(stroke
				(width 0.1524)
				(type default)
			)
			(layer "F.SilkS")
		)
		(fp_line
			(start 1.016 -2.2352)
			(end 1.016 2.2352)
			(stroke
				(width 0.1524)
				(type default)
			)
			(layer "F.SilkS")
		)
		(fp_rect
			(start -1.0922 2.3114)
			(end 1.0922 -2.3114)
			(stroke
				(width 0)
				(type default)
			)
			(fill no)
			(layer "F.CrtYd")
		)
		(fp_poly
			(pts
				(xy -1.0922 -2.3114) (xy 1.0922 -2.3114) (xy 1.0922 2.3114) (xy -1.0922 2.3114)
			)
			(stroke
				(width 0)
				(type default)
			)
			(fill no)
			(layer "F.Fab")
		)
		(pad "1" smd rect
			(at 0 -1.397 270)
			(size 1.651 1.27)
			(layers "F.Cu" "F.Mask" "F.Paste")
			(net "P12V_HDD33")
		)
		(pad "2" smd rect
			(at 0 1.397 270)
			(size 1.651 1.27)
			(layers "F.Cu" "F.Mask" "F.Paste")
			(net "12V_PRE_33")
		)
	)
	(footprint ""
		(layer "F.Cu")
		(at 361.369102 -181.842918 180)
		(property "Reference" "C287"
			(at 0 0 180)
			(layer "F.SilkS")
			(hide yes)
			(effects
				(font
					(size 1.27 1.27)
				)
			)
		)
		(property "Value" "SC1U16V3KX-5GP"
			(at 0 -2.8194 180)
			(unlocked yes)
			(layer "F.Fab")
			(hide yes)
			(effects
				(font
					(size 1.016 1.016)
					(thickness 0.1524)
				)
			)
		)
		(property "Device Type" "C603H36"
			(at 0 -4.3434 180)
			(unlocked yes)
			(layer "F.Fab")
			(hide yes)
			(effects
				(font
					(size 1.016 1.016)
					(thickness 0.1524)
				)
			)
		)
		(duplicate_pad_numbers_are_jumpers no)
		(fp_line
			(start 0.508 0)
			(end -0.508 0)
			(stroke
				(width 0.2032)
				(type default)
			)
			(layer "F.SilkS")
		)
		(fp_rect
			(start -0.5842 1.3335)
			(end 0.5842 -1.3335)
			(stroke
				(width 0)
				(type default)
			)
			(fill no)
			(layer "F.CrtYd")
		)
		(fp_rect
			(start -0.5842 1.3335)
			(end 0.5842 -1.3335)
			(stroke
				(width 0)
				(type default)
			)
			(fill no)
			(layer "F.Fab")
		)
		(pad "1" smd custom
			(at 0 -0.762 180)
			(size 0.2159 0.2159)
			(layers "F.Cu" "F.Mask" "F.Paste")
			(net "P5V_HDD19")
			(options
				(clearance outline)
				(anchor circle)
			)
			(primitives
				(gr_poly
					(pts
						(arc
							(start -0.3302 -0.4318)
							(mid -0.402042 -0.402042)
							(end -0.4318 -0.3302)
						)
						(arc
							(start -0.4318 0.3302)
							(mid -0.402042 0.402042)
							(end -0.3302 0.4318)
						)
						(arc
							(start 0.3302 0.4318)
							(mid 0.402042 0.402042)
							(end 0.4318 0.3302)
						)
						(arc
							(start 0.4318 -0.3302)
							(mid 0.402042 -0.402042)
							(end 0.3302 -0.4318)
						)
					)
					(width 0)
					(fill yes)
				)
			)
		)
		(pad "2" smd custom
			(at 0 0.762 180)
			(size 0.2159 0.2159)
			(layers "F.Cu" "F.Mask" "F.Paste")
			(net "GND")
			(options
				(clearance outline)
				(anchor circle)
			)
			(primitives
				(gr_poly
					(pts
						(arc
							(start -0.3302 -0.4318)
							(mid -0.402042 -0.402042)
							(end -0.4318 -0.3302)
						)
						(arc
							(start -0.4318 0.3302)
							(mid -0.402042 0.402042)
							(end -0.3302 0.4318)
						)
						(arc
							(start 0.3302 0.4318)
							(mid 0.402042 0.402042)
							(end 0.4318 0.3302)
						)
						(arc
							(start 0.4318 -0.3302)
							(mid 0.402042 -0.402042)
							(end 0.3302 -0.4318)
						)
					)
					(width 0)
					(fill yes)
				)
			)
		)
	)
	(footprint ""
		(layer "F.Cu")
		(at 477.739202 -158.939992 90)
		(property "Reference" "VIA11"
			(at 0 0 90)
			(layer "F.SilkS")
			(hide yes)
			(effects
				(font
					(size 1.27 1.27)
				)
			)
		)
		(property "Value" "100OHM-8L-1D6MM-L18L16-GP"
			(at -3.7211 -4.5085 90)
			(unlocked yes)
			(layer "F.Fab")
			(hide yes)
			(effects
				(font
					(size 1.016 1.016)
					(thickness 0.1524)
				)
			)
		)
		(property "Device Type" "VIA-PCIE-4P-394076"
			(at -3.7211 -6.0325 90)
			(unlocked yes)
			(layer "F.Fab")
			(hide yes)
			(effects
				(font
					(size 1.016 1.016)
					(thickness 0.1524)
				)
			)
		)
		(duplicate_pad_numbers_are_jumpers no)
		(fp_rect
			(start -1.9685 0.381)
			(end 1.9685 -0.381)
			(stroke
				(width 0)
				(type default)
			)
			(fill no)
			(layer "F.CrtYd")
		)
		(fp_rect
			(start -1.9685 0.381)
			(end 1.9685 -0.381)
			(stroke
				(width 0)
				(type default)
			)
			(fill no)
			(layer "F.Fab")
		)
		(pad "1" thru_hole circle
			(at -1.5875 0 90)
			(size 0.508 0.508)
			(drill 0.254)
			(layers "*.Cu" "*.Mask")
			(remove_unused_layers no)
			(net "GND")
			(clearance 0.127)
			(thermal_gap 0.127)
		)
		(pad "2" thru_hole circle
			(at -0.5715 0 90)
			(size 0.508 0.508)
			(drill 0.254)
			(layers "*.Cu" "*.Mask")
			(remove_unused_layers no)
			(net "PHY_SCC_A_TO_DRV_A_23_DP")
			(clearance 0.127)
			(thermal_gap 0.127)
		)
		(pad "3" thru_hole circle
			(at 0.5715 0 90)
			(size 0.508 0.508)
			(drill 0.254)
			(layers "*.Cu" "*.Mask")
			(remove_unused_layers no)
			(net "PHY_SCC_A_TO_DRV_A_23_DN")
			(clearance 0.127)
			(thermal_gap 0.127)
		)
		(pad "4" thru_hole circle
			(at 1.5875 0 90)
			(size 0.508 0.508)
			(drill 0.254)
			(layers "*.Cu" "*.Mask")
			(remove_unused_layers no)
			(net "GND")
			(clearance 0.127)
			(thermal_gap 0.127)
		)
	)
	(footprint ""
		(layer "F.Cu")
		(at 444.541402 -256.34315 180)
		(property "Reference" "R1260"
			(at 0 0 180)
			(layer "F.SilkS")
			(hide yes)
			(effects
				(font
					(size 1.27 1.27)
				)
			)
		)
		(property "Value" "619KR2F-GP"
			(at 0.064008 -3.993896 180)
			(unlocked yes)
			(layer "F.Fab")
			(hide yes)
			(effects
				(font
					(size 1.016 1.016)
					(thickness 0.1524)
				)
			)
		)
		(property "Device Type" "R402H16"
			(at 0.064008 -5.517896 180)
			(unlocked yes)
			(layer "F.Fab")
			(hide yes)
			(effects
				(font
					(size 1.016 1.016)
					(thickness 0.1524)
				)
			)
		)
		(duplicate_pad_numbers_are_jumpers no)
		(fp_line
			(start 0.508 -0.9398)
			(end -0.508 -0.9398)
			(stroke
				(width 0.1524)
				(type default)
			)
			(layer "F.SilkS")
		)
		(fp_line
			(start -0.508 -0.9398)
			(end -0.508 0.9398)
			(stroke
				(width 0.1524)
				(type default)
			)
			(layer "F.SilkS")
		)
		(fp_rect
			(start -0.508 0.9398)
			(end 0.508 -0.9398)
			(stroke
				(width 0)
				(type default)
			)
			(fill no)
			(layer "F.CrtYd")
		)
		(fp_rect
			(start -0.508 0.9398)
			(end 0.508 -0.9398)
			(stroke
				(width 0)
				(type default)
			)
			(fill no)
			(layer "F.Fab")
		)
		(pad "1" smd custom
			(at 0 -0.4445 180)
			(size 0.1397 0.1397)
			(layers "F.Cu" "F.Mask" "F.Paste")
			(net "P5V_C_RF")
			(options
				(clearance outline)
				(anchor circle)
			)
			(primitives
				(gr_poly
					(pts
						(arc
							(start -0.1778 -0.2794)
							(mid -0.249642 -0.249642)
							(end -0.2794 -0.1778)
						)
						(arc
							(start -0.2794 0.1778)
							(mid -0.249642 0.249642)
							(end -0.1778 0.2794)
						)
						(arc
							(start 0.1778 0.2794)
							(mid 0.249642 0.249642)
							(end 0.2794 0.1778)
						)
						(arc
							(start 0.2794 -0.1778)
							(mid 0.249642 -0.249642)
							(end 0.1778 -0.2794)
						)
					)
					(width 0)
					(fill yes)
				)
			)
		)
		(pad "2" smd custom
			(at 0 0.4445 180)
			(size 0.1397 0.1397)
			(layers "F.Cu" "F.Mask" "F.Paste")
			(net "AGND_P5V_C")
			(options
				(clearance outline)
				(anchor circle)
			)
			(primitives
				(gr_poly
					(pts
						(arc
							(start -0.1778 -0.2794)
							(mid -0.249642 -0.249642)
							(end -0.2794 -0.1778)
						)
						(arc
							(start -0.2794 0.1778)
							(mid -0.249642 0.249642)
							(end -0.1778 0.2794)
						)
						(arc
							(start 0.1778 0.2794)
							(mid 0.249642 0.249642)
							(end 0.2794 0.1778)
						)
						(arc
							(start 0.2794 -0.1778)
							(mid 0.249642 -0.249642)
							(end 0.1778 -0.2794)
						)
					)
					(width 0)
					(fill yes)
				)
			)
		)
	)
	(footprint ""
		(layer "F.Cu")
		(at 244.221 -231.14)
		(property "Reference" "R78"
			(at 0 0 0)
			(layer "F.SilkS")
			(hide yes)
			(effects
				(font
					(size 1.27 1.27)
				)
			)
		)
		(property "Value" "4K7R2F-GP"
			(at 0.064008 -3.993896 0)
			(unlocked yes)
			(layer "F.Fab")
			(hide yes)
			(effects
				(font
					(size 1.016 1.016)
					(thickness 0.1524)
				)
			)
		)
		(property "Device Type" "R402H16"
			(at 0.064008 -5.517896 0)
			(unlocked yes)
			(layer "F.Fab")
			(hide yes)
			(effects
				(font
					(size 1.016 1.016)
					(thickness 0.1524)
				)
			)
		)
		(duplicate_pad_numbers_are_jumpers no)
		(fp_line
			(start -0.508 -0.9398)
			(end -0.508 0.9398)
			(stroke
				(width 0.1524)
				(type default)
			)
			(layer "F.SilkS")
		)
		(fp_line
			(start 0.508 -0.9398)
			(end -0.508 -0.9398)
			(stroke
				(width 0.1524)
				(type default)
			)
			(layer "F.SilkS")
		)
		(fp_rect
			(start -0.508 0.9398)
			(end 0.508 -0.9398)
			(stroke
				(width 0)
				(type default)
			)
			(fill no)
			(layer "F.CrtYd")
		)
		(fp_rect
			(start -0.508 0.9398)
			(end 0.508 -0.9398)
			(stroke
				(width 0)
				(type default)
			)
			(fill no)
			(layer "F.Fab")
		)
		(pad "1" smd custom
			(at 0 -0.4445)
			(size 0.1397 0.1397)
			(layers "F.Cu" "F.Mask" "F.Paste")
			(net "IO_EXP2_A1")
			(options
				(clearance outline)
				(anchor circle)
			)
			(primitives
				(gr_poly
					(pts
						(arc
							(start -0.1778 -0.2794)
							(mid -0.249642 -0.249642)
							(end -0.2794 -0.1778)
						)
						(arc
							(start -0.2794 0.1778)
							(mid -0.249642 0.249642)
							(end -0.1778 0.2794)
						)
						(arc
							(start 0.1778 0.2794)
							(mid 0.249642 0.249642)
							(end 0.2794 0.1778)
						)
						(arc
							(start 0.2794 -0.1778)
							(mid 0.249642 -0.249642)
							(end 0.1778 -0.2794)
						)
					)
					(width 0)
					(fill yes)
				)
			)
		)
		(pad "2" smd custom
			(at 0 0.4445)
			(size 0.1397 0.1397)
			(layers "F.Cu" "F.Mask" "F.Paste")
			(net "GND")
			(options
				(clearance outline)
				(anchor circle)
			)
			(primitives
				(gr_poly
					(pts
						(arc
							(start -0.1778 -0.2794)
							(mid -0.249642 -0.249642)
							(end -0.2794 -0.1778)
						)
						(arc
							(start -0.2794 0.1778)
							(mid -0.249642 0.249642)
							(end -0.1778 0.2794)
						)
						(arc
							(start 0.1778 0.2794)
							(mid 0.249642 0.249642)
							(end 0.2794 0.1778)
						)
						(arc
							(start 0.2794 -0.1778)
							(mid 0.249642 -0.249642)
							(end 0.1778 -0.2794)
						)
					)
					(width 0)
					(fill yes)
				)
			)
		)
	)
	(footprint ""
		(layer "F.Cu")
		(at 458.5589 -180.826918 180)
		(property "Reference" "C327"
			(at 0 0 180)
			(layer "F.SilkS")
			(hide yes)
			(effects
				(font
					(size 1.27 1.27)
				)
			)
		)
		(property "Value" "SC10U16V6KX-2GP"
			(at -0.0762 -5.1308 180)
			(unlocked yes)
			(layer "F.Fab")
			(hide yes)
			(effects
				(font
					(size 1.016 1.016)
					(thickness 0.1524)
				)
			)
		)
		(property "Device Type" "C1206H71"
			(at -0.127 -6.6548 180)
			(unlocked yes)
			(layer "F.Fab")
			(hide yes)
			(effects
				(font
					(size 1.016 1.016)
					(thickness 0.1524)
				)
			)
		)
		(duplicate_pad_numbers_are_jumpers no)
		(fp_line
			(start 1.016 2.2352)
			(end -1.016 2.2352)
			(stroke
				(width 0.1524)
				(type default)
			)
			(layer "F.SilkS")
		)
		(fp_line
			(start 1.016 0.8382)
			(end 1.016 2.2352)
			(stroke
				(width 0.1524)
				(type default)
			)
			(layer "F.SilkS")
		)
		(fp_line
			(start 1.016 -2.2352)
			(end 1.016 -0.8382)
			(stroke
				(width 0.1524)
				(type default)
			)
			(layer "F.SilkS")
		)
		(fp_line
			(start -1.016 2.2352)
			(end -1.016 0.8382)
			(stroke
				(width 0.1524)
				(type default)
			)
			(layer "F.SilkS")
		)
		(fp_line
			(start -1.016 -0.8382)
			(end -1.016 -2.2352)
			(stroke
				(width 0.1524)
				(type default)
			)
			(layer "F.SilkS")
		)
		(fp_line
			(start -1.016 -2.2352)
			(end 1.016 -2.2352)
			(stroke
				(width 0.1524)
				(type default)
			)
			(layer "F.SilkS")
		)
		(fp_rect
			(start -1.0922 2.3114)
			(end 1.0922 -2.3114)
			(stroke
				(width 0)
				(type default)
			)
			(fill no)
			(layer "F.CrtYd")
		)
		(fp_poly
			(pts
				(xy 1.0922 -2.3114) (xy 1.0922 2.3114) (xy -1.0922 2.3114) (xy -1.0922 -2.3114)
			)
			(stroke
				(width 0)
				(type default)
			)
			(fill no)
			(layer "F.Fab")
		)
		(pad "1" smd rect
			(at 0 -1.397 180)
			(size 1.651 1.27)
			(layers "F.Cu" "F.Mask" "F.Paste")
			(net "P5V_HDD22")
		)
		(pad "2" smd rect
			(at 0 1.397 180)
			(size 1.651 1.27)
			(layers "F.Cu" "F.Mask" "F.Paste")
			(net "GND")
		)
	)
	(footprint ""
		(layer "F.Cu")
		(at 261.932166 -336.350864 90)
		(property "Reference" "R386"
			(at 0 0 90)
			(layer "F.SilkS")
			(hide yes)
			(effects
				(font
					(size 1.27 1.27)
				)
			)
		)
		(property "Value" "10KR2F-2-GP"
			(at 0.064008 -3.993896 90)
			(unlocked yes)
			(layer "F.Fab")
			(hide yes)
			(effects
				(font
					(size 1.016 1.016)
					(thickness 0.1524)
				)
			)
		)
		(property "Device Type" "R402H16"
			(at 0.064008 -5.517896 90)
			(unlocked yes)
			(layer "F.Fab")
			(hide yes)
			(effects
				(font
					(size 1.016 1.016)
					(thickness 0.1524)
				)
			)
		)
		(duplicate_pad_numbers_are_jumpers no)
		(fp_line
			(start 0.508 -0.9398)
			(end -0.508 -0.9398)
			(stroke
				(width 0.1524)
				(type default)
			)
			(layer "F.SilkS")
		)
		(fp_line
			(start -0.508 -0.9398)
			(end -0.508 0.9398)
			(stroke
				(width 0.1524)
				(type default)
			)
			(layer "F.SilkS")
		)
		(fp_rect
			(start -0.508 0.9398)
			(end 0.508 -0.9398)
			(stroke
				(width 0)
				(type default)
			)
			(fill no)
			(layer "F.CrtYd")
		)
		(fp_rect
			(start -0.508 0.9398)
			(end 0.508 -0.9398)
			(stroke
				(width 0)
				(type default)
			)
			(fill no)
			(layer "F.Fab")
		)
		(pad "1" smd custom
			(at 0 -0.4445 90)
			(size 0.1397 0.1397)
			(layers "F.Cu" "F.Mask" "F.Paste")
			(net "P3V3_STBY_A")
			(options
				(clearance outline)
				(anchor circle)
			)
			(primitives
				(gr_poly
					(pts
						(arc
							(start -0.1778 -0.2794)
							(mid -0.249642 -0.249642)
							(end -0.2794 -0.1778)
						)
						(arc
							(start -0.2794 0.1778)
							(mid -0.249642 0.249642)
							(end -0.1778 0.2794)
						)
						(arc
							(start 0.1778 0.2794)
							(mid 0.249642 0.249642)
							(end 0.2794 0.1778)
						)
						(arc
							(start 0.2794 -0.1778)
							(mid 0.249642 -0.249642)
							(end 0.1778 -0.2794)
						)
					)
					(width 0)
					(fill yes)
				)
			)
		)
		(pad "2" smd custom
			(at 0 0.4445 90)
			(size 0.1397 0.1397)
			(layers "F.Cu" "F.Mask" "F.Paste")
			(net "SCC_A_TYPE_2")
			(options
				(clearance outline)
				(anchor circle)
			)
			(primitives
				(gr_poly
					(pts
						(arc
							(start -0.1778 -0.2794)
							(mid -0.249642 -0.249642)
							(end -0.2794 -0.1778)
						)
						(arc
							(start -0.2794 0.1778)
							(mid -0.249642 0.249642)
							(end -0.1778 0.2794)
						)
						(arc
							(start 0.1778 0.2794)
							(mid 0.249642 0.249642)
							(end 0.2794 0.1778)
						)
						(arc
							(start 0.2794 -0.1778)
							(mid 0.249642 -0.249642)
							(end 0.1778 -0.2794)
						)
					)
					(width 0)
					(fill yes)
				)
			)
		)
	)
	(footprint ""
		(layer "F.Cu")
		(at 86.832948 -177.270918)
		(property "Reference" "R451"
			(at 0 0 0)
			(layer "F.SilkS")
			(hide yes)
			(effects
				(font
					(size 1.27 1.27)
				)
			)
		)
		(property "Value" "2R6F-GP"
			(at -0.0508 -4.8514 0)
			(unlocked yes)
			(layer "F.Fab")
			(hide yes)
			(effects
				(font
					(size 1.016 1.016)
					(thickness 0.1524)
				)
			)
		)
		(property "Device Type" "R1206H26"
			(at 0 -6.3754 0)
			(unlocked yes)
			(layer "F.Fab")
			(hide yes)
			(effects
				(font
					(size 1.016 1.016)
					(thickness 0.1524)
				)
			)
		)
		(duplicate_pad_numbers_are_jumpers no)
		(fp_line
			(start -1.016 -2.2352)
			(end 1.016 -2.2352)
			(stroke
				(width 0.1524)
				(type default)
			)
			(layer "F.SilkS")
		)
		(fp_line
			(start -1.016 2.2352)
			(end -1.016 -2.2352)
			(stroke
				(width 0.1524)
				(type default)
			)
			(layer "F.SilkS")
		)
		(fp_line
			(start 1.016 -2.2352)
			(end 1.016 2.2352)
			(stroke
				(width 0.1524)
				(type default)
			)
			(layer "F.SilkS")
		)
		(fp_line
			(start 1.016 2.2352)
			(end -1.016 2.2352)
			(stroke
				(width 0.1524)
				(type default)
			)
			(layer "F.SilkS")
		)
		(fp_rect
			(start -1.0922 2.3114)
			(end 1.0922 -2.3114)
			(stroke
				(width 0)
				(type default)
			)
			(fill no)
			(layer "F.CrtYd")
		)
		(fp_poly
			(pts
				(xy -1.0922 -2.3114) (xy 1.0922 -2.3114) (xy 1.0922 2.3114) (xy -1.0922 2.3114)
			)
			(stroke
				(width 0)
				(type default)
			)
			(fill no)
			(layer "F.Fab")
		)
		(pad "1" smd rect
			(at 0 -1.397)
			(size 1.651 1.27)
			(layers "F.Cu" "F.Mask" "F.Paste")
			(net "P5V_HDD14")
		)
		(pad "2" smd rect
			(at 0 1.397)
			(size 1.651 1.27)
			(layers "F.Cu" "F.Mask" "F.Paste")
			(net "5V_PRE_14")
		)
	)
)
